# T6G (Grand Teton) — schematic netlist excerpt (pin names and nets, part order shuffled) for the footprints in the layout excerpt that follows; sources: Cadence DE-HDL packaged netlist, KiCad conversion of 04192023_DAF0TMB3IC0_F0TG_MB_C_brd_V02_OCP.brd

C1110  Q_CAP  0.1UF 25V 10% X7R  pkg 0402  page 357 : A = VSENSE_P12V_INA230_8_INP ; B = VSENSE_P12V_INA230_8_INN
R372  Q_RES  33 5% CHIP  pkg 0402LF  page 81 : A = P12V_ALL_PWROK_R ; B = P12V_ALL_PWROK

(kicad_pcb
	(version 20260206)
	(generator "pcbnew")
	(generator_version "10.0")
	(general
		(thickness 1.6)
		(legacy_teardrops no)
	)
	(paper "A4")
	(title_block
		(title "04192023_DAF0TMB3IC0_F0TG_MB_C_brd_V02_OCP.brd")
		(comment 1 "Grand Teton / footprints 4757-4758 of 8354")
	)
	(layers
		(0 "F.Cu" signal "TOP")
		(4 "In1.Cu" signal "GND")
		(6 "In2.Cu" signal "IN1")
		(8 "In3.Cu" signal "GND1")
		(10 "In4.Cu" signal "IN2")
		(12 "In5.Cu" signal "GND2")
		(14 "In6.Cu" signal "IN3")
		(16 "In7.Cu" signal "GND3")
		(18 "In8.Cu" signal "VCC")
		(20 "In9.Cu" signal "VCC1")
		(22 "In10.Cu" signal "GND4")
		(24 "In11.Cu" signal "IN4")
		(26 "In12.Cu" signal "GND5")
		(28 "In13.Cu" signal "IN5")
		(30 "In14.Cu" signal "GND6")
		(32 "In15.Cu" signal "IN6")
		(34 "In16.Cu" signal "GND7")
		(2 "B.Cu" signal "BOTTOM")
		(9 "F.Adhes" user "F.Adhesive")
		(11 "B.Adhes" user "B.Adhesive")
		(13 "F.Paste" user "Package Geometry/Pastemask Top")
		(15 "B.Paste" user "Package Geometry/Pastemask Bottom")
		(5 "F.SilkS" user "Ref Des/Silkscreen Top")
		(7 "B.SilkS" user "Ref Des/Silkscreen Bottom")
		(1 "F.Mask" user "Board Geometry/Soldermask Top")
		(3 "B.Mask" user "Board Geometry/Soldermask Bottom")
		(17 "Dwgs.User" user "User.Drawings")
		(19 "Cmts.User" user "User.Comments")
		(21 "Eco1.User" user "User.Eco1")
		(23 "Eco2.User" user "User.Eco2")
		(25 "Edge.Cuts" user "Board Geometry/Outline")
		(27 "Margin" user)
		(31 "F.CrtYd" user "Package Geometry/Place Bound Top")
		(29 "B.CrtYd" user "Package Geometry/Place Bound Bottom")
		(35 "F.Fab" user "Ref Des/Assembly Top")
		(33 "B.Fab" user "Ref Des/Assembly Bottom")
	)
	(footprint ""
		(layer "F.Cu")
		(at 193.167 -133.568948 90)
		(property "Reference" "R372"
			(at 0 0 90)
			(layer "F.SilkS")
			(hide yes)
			(effects
				(font
					(size 1.27 1.27)
				)
			)
		)
		(property "Value" ""
			(at 0 0 90)
			(layer "F.Fab")
			(effects
				(font
					(size 1.27 1.27)
				)
			)
		)
		(duplicate_pad_numbers_are_jumpers no)
		(fp_line
			(start 0.7874 -0.4064)
			(end 0.7874 0.4064)
			(stroke
				(width 0.1524)
				(type default)
			)
			(layer "F.SilkS")
		)
		(fp_line
			(start -0.7874 -0.4064)
			(end 0.7874 -0.4064)
			(stroke
				(width 0.1524)
				(type default)
			)
			(layer "F.SilkS")
		)
		(fp_line
			(start 0.7874 0.4064)
			(end -0.7874 0.4064)
			(stroke
				(width 0.1524)
				(type default)
			)
			(layer "F.SilkS")
		)
		(fp_line
			(start -0.7874 0.4064)
			(end -0.7874 -0.4064)
			(stroke
				(width 0.1524)
				(type default)
			)
			(layer "F.SilkS")
		)
		(fp_line
			(start -0.12065 -0.305054)
			(end -0.12065 -0.2794)
			(stroke
				(width 0.1)
				(type default)
			)
			(layer "F.Fab")
		)
		(fp_line
			(start -0.67945 -0.305054)
			(end -0.12065 -0.305054)
			(stroke
				(width 0.1)
				(type default)
			)
			(layer "F.Fab")
		)
		(fp_line
			(start 0.67945 -0.3048)
			(end 0.67945 0.3048)
			(stroke
				(width 0.1)
				(type default)
			)
			(layer "F.Fab")
		)
		(fp_line
			(start 0.12065 -0.3048)
			(end 0.67945 -0.3048)
			(stroke
				(width 0.1)
				(type default)
			)
			(layer "F.Fab")
		)
		(fp_line
			(start 0.12065 -0.2794)
			(end 0.12065 -0.3048)
			(stroke
				(width 0.1)
				(type default)
			)
			(layer "F.Fab")
		)
		(fp_line
			(start -0.12065 -0.2794)
			(end 0.12065 -0.2794)
			(stroke
				(width 0.1)
				(type default)
			)
			(layer "F.Fab")
		)
		(fp_line
			(start 0.120396 0.2794)
			(end -0.12065 0.2794)
			(stroke
				(width 0.1)
				(type default)
			)
			(layer "F.Fab")
		)
		(fp_line
			(start -0.12065 0.2794)
			(end -0.12065 0.3048)
			(stroke
				(width 0.1)
				(type default)
			)
			(layer "F.Fab")
		)
		(fp_line
			(start 0.67945 0.3048)
			(end 0.120396 0.3048)
			(stroke
				(width 0.1)
				(type default)
			)
			(layer "F.Fab")
		)
		(fp_line
			(start 0.120396 0.3048)
			(end 0.120396 0.2794)
			(stroke
				(width 0.1)
				(type default)
			)
			(layer "F.Fab")
		)
		(fp_line
			(start -0.12065 0.3048)
			(end -0.67945 0.3048)
			(stroke
				(width 0.1)
				(type default)
			)
			(layer "F.Fab")
		)
		(fp_line
			(start -0.67945 0.3048)
			(end -0.67945 -0.305054)
			(stroke
				(width 0.1)
				(type default)
			)
			(layer "F.Fab")
		)
		(pad "1" smd circle
			(at -0.40005 0 90)
			(size 0 0)
			(layers "F.Cu" "F.Mask" "F.Paste")
			(net "P12V_ALL_PWROK_R")
		)
		(pad "2" smd circle
			(at 0.40005 0 90)
			(size 0 0)
			(layers "F.Cu" "F.Mask" "F.Paste")
			(net "P12V_ALL_PWROK")
		)
	)
	(footprint ""
		(layer "F.Cu")
		(at 244.63375 -51.332384 180)
		(property "Reference" "C1110"
			(at 0 0 180)
			(layer "F.SilkS")
			(hide yes)
			(effects
				(font
					(size 1.27 1.27)
				)
			)
		)
		(property "Value" ""
			(at 0 0 180)
			(layer "F.Fab")
			(effects
				(font
					(size 1.27 1.27)
				)
			)
		)
		(duplicate_pad_numbers_are_jumpers no)
		(fp_line
			(start 0.7874 0.4064)
			(end -0.7874 0.4064)
			(stroke
				(width 0.1524)
				(type default)
			)
			(layer "F.SilkS")
		)
		(fp_line
			(start 0.7874 -0.4064)
			(end 0.7874 0.4064)
			(stroke
				(width 0.1524)
				(type default)
			)
			(layer "F.SilkS")
		)
		(fp_line
			(start -0.7874 0.4064)
			(end -0.7874 -0.4064)
			(stroke
				(width 0.1524)
				(type default)
			)
			(layer "F.SilkS")
		)
		(fp_line
			(start -0.7874 -0.4064)
			(end 0.7874 -0.4064)
			(stroke
				(width 0.1524)
				(type default)
			)
			(layer "F.SilkS")
		)
		(fp_line
			(start 0.67945 0.3048)
			(end 0.120396 0.3048)
			(stroke
				(width 0.1)
				(type default)
			)
			(layer "F.Fab")
		)
		(fp_line
			(start 0.67945 -0.3048)
			(end 0.67945 0.3048)
			(stroke
				(width 0.1)
				(type default)
			)
			(layer "F.Fab")
		)
		(fp_line
			(start 0.12065 -0.2794)
			(end 0.12065 -0.3048)
			(stroke
				(width 0.1)
				(type default)
			)
			(layer "F.Fab")
		)
		(fp_line
			(start 0.12065 -0.3048)
			(end 0.67945 -0.3048)
			(stroke
				(width 0.1)
				(type default)
			)
			(layer "F.Fab")
		)
		(fp_line
			(start 0.120396 0.3048)
			(end 0.120396 0.2794)
			(stroke
				(width 0.1)
				(type default)
			)
			(layer "F.Fab")
		)
		(fp_line
			(start 0.120396 0.2794)
			(end -0.12065 0.2794)
			(stroke
				(width 0.1)
				(type default)
			)
			(layer "F.Fab")
		)
		(fp_line
			(start -0.12065 0.3048)
			(end -0.67945 0.3048)
			(stroke
				(width 0.1)
				(type default)
			)
			(layer "F.Fab")
		)
		(fp_line
			(start -0.12065 0.2794)
			(end -0.12065 0.3048)
			(stroke
				(width 0.1)
				(type default)
			)
			(layer "F.Fab")
		)
		(fp_line
			(start -0.12065 -0.2794)
			(end 0.12065 -0.2794)
			(stroke
				(width 0.1)
				(type default)
			)
			(layer "F.Fab")
		)
		(fp_line
			(start -0.12065 -0.305054)
			(end -0.12065 -0.2794)
			(stroke
				(width 0.1)
				(type default)
			)
			(layer "F.Fab")
		)
		(fp_line
			(start -0.67945 0.3048)
			(end -0.67945 -0.305054)
			(stroke
				(width 0.1)
				(type default)
			)
			(layer "F.Fab")
		)
		(fp_line
			(start -0.67945 -0.305054)
			(end -0.12065 -0.305054)
			(stroke
				(width 0.1)
				(type default)
			)
			(layer "F.Fab")
		)
		(pad "1" smd circle
			(at -0.40005 0 180)
			(size 0 0)
			(layers "F.Cu" "F.Mask" "F.Paste")
			(net "VSENSE_P12V_INA230_8_INP")
		)
		(pad "2" smd circle
			(at 0.40005 0 180)
			(size 0 0)
			(layers "F.Cu" "F.Mask" "F.Paste")
			(net "VSENSE_P12V_INA230_8_INN")
		)
	)
)
